G04 ================== begin FILE IDENTIFICATION RECORD ==================*
G04 Layout Name:  17301-sa.brd*
G04 Film Name:    L5GND*
G04 File Format:  Gerber RS274X*
G04 File Origin:  Cadence Allegro 16.6-2015-S079*
G04 Origin Date:  Thu Jun 22 17:50:04 2017*
G04 *
G04 Layer:  VIA CLASS/L5GND*
G04 Layer:  PIN/L5GND*
G04 Layer:  ETCH/L5GND*
G04 Layer:  DRAWING FORMAT/LAYER_PCB_STORY*
G04 Layer:  DRAWING FORMAT/LAYER_L5GND*
G04 *
G04 Offset:    (0.00 0.00)*
G04 Mirror:    No*
G04 Mode:      Negative*
G04 Rotation:  0*
G04 FullContactRelief:  No*
G04 UndefLineWidth:     6.00*
G04 ================== end FILE IDENTIFICATION RECORD ====================*
%FSLAX35Y35*MOIN*%
%IR0*IPPOS*OFA0.00000B0.00000*MIA0B0*SFA1.00000B1.00000*%
%AMMACRO26*
4,1,15,-.03299,.01885,
-.035762,.012835,
-.037448,.00643,
-.037995,-.00017,
-.037388,-.006766,
-.035646,-.013155,
-.03299,-.01885,
-.03664,-.0225,
-.03999,-.015796,
-.042126,-.008611,
-.042981,-.001166,
-.042531,.006316,
-.040788,.013605,
-.037806,.020481,
-.03664,.0225,
-.03299,.01885,
0.0*
4,1,15,-.01885,-.03299,
-.012835,-.035762,
-.00643,-.037448,
.00017,-.037995,
.006766,-.037388,
.013155,-.035646,
.01885,-.03299,
.0225,-.03664,
.015796,-.03999,
.008611,-.042126,
.001166,-.042981,
-.006316,-.042531,
-.013605,-.040788,
-.020481,-.037806,
-.0225,-.03664,
-.01885,-.03299,
0.0*
4,1,15,.03299,-.01885,
.035762,-.012835,
.037448,-.00643,
.037995,.00017,
.037388,.006766,
.035646,.013155,
.03299,.01885,
.03664,.0225,
.03999,.015796,
.042126,.008611,
.042981,.001166,
.042531,-.006316,
.040788,-.013605,
.037806,-.020481,
.03664,-.0225,
.03299,-.01885,
0.0*
4,1,15,.01885,.03299,
.012835,.035762,
.00643,.037448,
-.00017,.037995,
-.006766,.037388,
-.013155,.035646,
-.01885,.03299,
-.0225,.03664,
-.015796,.03999,
-.008611,.042126,
-.001166,.042981,
.006316,.042531,
.013605,.040788,
.020481,.037806,
.0225,.03664,
.01885,.03299,
0.0*
%
%ADD26MACRO26*%
%ADD16C,.03*%
%ADD15C,.032*%
%ADD19C,.044*%
%ADD20C,.081*%
%ADD17C,.048*%
%ADD22C,.076*%
%ADD25C,.086*%
%ADD24C,.078*%
%AMMACRO13*
4,1,19,.00048,.00013,
.000487,.000102,
.000492,.000073,
.000495,.000045,
.000497,.000016,
.000497,-.000013,
.000496,-.000042,
.000492,-.000071,
.000487,-.000099,
.000481,-.000127,
.00048,-.00013,
.00086,-.00051,
.000935,-.000353,
.000983,-.000185,
.001,-.000012,
.000987,.000162,
.000943,.000331,
.000872,.00049,
.00086,.00051,
.00048,.00013,
0.0*
4,1,19,.00013,-.00048,
.000102,-.000487,
.000073,-.000492,
.000045,-.000495,
.000016,-.000497,
-.000013,-.000497,
-.000042,-.000496,
-.000071,-.000492,
-.000099,-.000487,
-.000127,-.000481,
-.00013,-.00048,
-.00051,-.00086,
-.000353,-.000935,
-.000185,-.000983,
-.000012,-.001,
.000162,-.000987,
.000331,-.000943,
.00049,-.000872,
.00051,-.00086,
.00013,-.00048,
0.0*
4,1,19,-.00048,-.00013,
-.000487,-.000102,
-.000492,-.000073,
-.000495,-.000045,
-.000497,-.000016,
-.000497,.000013,
-.000496,.000042,
-.000492,.000071,
-.000487,.000099,
-.000481,.000127,
-.00048,.00013,
-.00086,.00051,
-.000935,.000353,
-.000983,.000185,
-.001,.000012,
-.000987,-.000162,
-.000943,-.000331,
-.000872,-.00049,
-.00086,-.00051,
-.00048,-.00013,
0.0*
4,1,19,-.00013,.00048,
-.000102,.000487,
-.000073,.000492,
-.000045,.000495,
-.000016,.000497,
.000013,.000497,
.000042,.000496,
.000071,.000492,
.000099,.000487,
.000127,.000481,
.00013,.00048,
.00051,.00086,
.000353,.000935,
.000185,.000983,
.000012,.001,
-.000162,.000987,
-.000331,.000943,
-.00049,.000872,
-.00051,.00086,
-.00013,.00048,
0.0*
%
%ADD13MACRO13*%
%ADD14C,.105*%
%ADD10C,.114*%
%ADD21O,.098X.06*%
%AMMACRO23*
4,1,19,.00048,.00013,
.000487,.000102,
.000492,.000073,
.000495,.000045,
.000497,.000016,
.000497,-.000013,
.000496,-.000042,
.000492,-.000071,
.000487,-.000099,
.000481,-.000127,
.00048,-.00013,
.00086,-.00051,
.000935,-.000353,
.000983,-.000185,
.001,-.000012,
.000987,.000162,
.000943,.000331,
.000872,.00049,
.00086,.00051,
.00048,.00013,
270.*
4,1,19,.00013,-.00048,
.000102,-.000487,
.000073,-.000492,
.000045,-.000495,
.000016,-.000497,
-.000013,-.000497,
-.000042,-.000496,
-.000071,-.000492,
-.000099,-.000487,
-.000127,-.000481,
-.00013,-.00048,
-.00051,-.00086,
-.000353,-.000935,
-.000185,-.000983,
-.000012,-.001,
.000162,-.000987,
.000331,-.000943,
.00049,-.000872,
.00051,-.00086,
.00013,-.00048,
270.*
4,1,19,-.00048,-.00013,
-.000487,-.000102,
-.000492,-.000073,
-.000495,-.000045,
-.000497,-.000016,
-.000497,.000013,
-.000496,.000042,
-.000492,.000071,
-.000487,.000099,
-.000481,.000127,
-.00048,.00013,
-.00086,.00051,
-.000935,.000353,
-.000983,.000185,
-.001,.000012,
-.000987,-.000162,
-.000943,-.000331,
-.000872,-.00049,
-.00086,-.00051,
-.00048,-.00013,
270.*
4,1,19,-.00013,.00048,
-.000102,.000487,
-.000073,.000492,
-.000045,.000495,
-.000016,.000497,
.000013,.000497,
.000042,.000496,
.000071,.000492,
.000099,.000487,
.000127,.000481,
.00013,.00048,
.00051,.00086,
.000353,.000935,
.000185,.000983,
.000012,.001,
-.000162,.000987,
-.000331,.000943,
-.00049,.000872,
-.00051,.00086,
-.00013,.00048,
270.*
%
%ADD23MACRO23*%
%AMMACRO18*
4,1,19,.00048,.00013,
.000487,.000102,
.000492,.000073,
.000495,.000045,
.000497,.000016,
.000497,-.000013,
.000496,-.000042,
.000492,-.000071,
.000487,-.000099,
.000481,-.000127,
.00048,-.00013,
.00086,-.00051,
.000935,-.000353,
.000983,-.000185,
.001,-.000012,
.000987,.000162,
.000943,.000331,
.000872,.00049,
.00086,.00051,
.00048,.00013,
180.*
4,1,19,.00013,-.00048,
.000102,-.000487,
.000073,-.000492,
.000045,-.000495,
.000016,-.000497,
-.000013,-.000497,
-.000042,-.000496,
-.000071,-.000492,
-.000099,-.000487,
-.000127,-.000481,
-.00013,-.00048,
-.00051,-.00086,
-.000353,-.000935,
-.000185,-.000983,
-.000012,-.001,
.000162,-.000987,
.000331,-.000943,
.00049,-.000872,
.00051,-.00086,
.00013,-.00048,
180.*
4,1,19,-.00048,-.00013,
-.000487,-.000102,
-.000492,-.000073,
-.000495,-.000045,
-.000497,-.000016,
-.000497,.000013,
-.000496,.000042,
-.000492,.000071,
-.000487,.000099,
-.000481,.000127,
-.00048,.00013,
-.00086,.00051,
-.000935,.000353,
-.000983,.000185,
-.001,.000012,
-.000987,-.000162,
-.000943,-.000331,
-.000872,-.00049,
-.00086,-.00051,
-.00048,-.00013,
180.*
4,1,19,-.00013,.00048,
-.000102,.000487,
-.000073,.000492,
-.000045,.000495,
-.000016,.000497,
.000013,.000497,
.000042,.000496,
.000071,.000492,
.000099,.000487,
.000127,.000481,
.00013,.00048,
.00051,.00086,
.000353,.000935,
.000185,.000983,
.000012,.001,
-.000162,.000987,
-.000331,.000943,
-.00049,.000872,
-.00051,.00086,
-.00013,.00048,
180.*
%
%ADD18MACRO18*%
%AMMACRO12*
4,1,16,.06891,.04063,
.074918,.028047,
.07865,.014611,
.079993,.000732,
.078905,-.01317,
.075419,-.026672,
.069642,-.039363,
.06891,-.04063,
.07256,-.04427,
.079145,-.030998,
.083325,-.016783,
.084974,-.002059,
.08404,.012728,
.080553,.027128,
.074619,.040704,
.07256,.04427,
.06891,.04063,
0.0*
4,1,16,.04063,-.06891,
.028047,-.074918,
.014611,-.07865,
.000732,-.079993,
-.01317,-.078905,
-.026672,-.075419,
-.039363,-.069642,
-.04063,-.06891,
-.04427,-.07256,
-.030998,-.079145,
-.016783,-.083325,
-.002059,-.084974,
.012728,-.08404,
.027128,-.080553,
.040704,-.074619,
.04427,-.07256,
.04063,-.06891,
0.0*
4,1,16,-.06891,-.04063,
-.074918,-.028047,
-.07865,-.014611,
-.079993,-.000732,
-.078905,.01317,
-.075419,.026672,
-.069642,.039363,
-.06891,.04063,
-.07256,.04427,
-.079145,.030998,
-.083325,.016783,
-.084974,.002059,
-.08404,-.012728,
-.080553,-.027128,
-.074619,-.040704,
-.07256,-.04427,
-.06891,-.04063,
0.0*
4,1,16,-.04063,.06891,
-.028047,.074918,
-.014611,.07865,
-.000732,.079993,
.01317,.078905,
.026672,.075419,
.039363,.069642,
.04063,.06891,
.04427,.07256,
.030998,.079145,
.016783,.083325,
.002059,.084974,
-.012728,.08404,
-.027128,.080553,
-.040704,.074619,
-.04427,.07256,
-.04063,.06891,
0.0*
%
%ADD12MACRO12*%
%AMMACRO11*
4,1,16,.09594,-.02,
.091009,-.036356,
.083314,-.051607,
.073086,-.065291,
.060639,-.07699,
.046348,-.08635,
.030649,-.093086,
.02,-.09594,
.02,-.10104,
.037242,-.096032,
.053352,-.088106,
.067841,-.077503,
.080268,-.064545,
.090257,-.049626,
.097503,-.033199,
.10104,-.02,
.09594,-.02,
0.0*
4,1,16,-.02,-.09594,
-.036356,-.091009,
-.051607,-.083314,
-.065291,-.073086,
-.07699,-.060639,
-.08635,-.046348,
-.093086,-.030649,
-.09594,-.02,
-.10104,-.02,
-.096032,-.037242,
-.088106,-.053352,
-.077503,-.067841,
-.064545,-.080268,
-.049626,-.090257,
-.033199,-.097503,
-.02,-.10104,
-.02,-.09594,
0.0*
4,1,16,-.09594,.02,
-.091009,.036356,
-.083314,.051607,
-.073086,.065291,
-.060639,.07699,
-.046348,.08635,
-.030649,.093086,
-.02,.09594,
-.02,.10104,
-.037242,.096032,
-.053352,.088106,
-.067841,.077503,
-.080268,.064545,
-.090257,.049626,
-.097503,.033199,
-.10104,.02,
-.09594,.02,
0.0*
4,1,16,.02,.09594,
.036356,.091009,
.051607,.083314,
.065291,.073086,
.07699,.060639,
.08635,.046348,
.093086,.030649,
.09594,.02,
.10104,.02,
.096032,.037242,
.088106,.053352,
.077503,.067841,
.064545,.080268,
.049626,.090257,
.033199,.097503,
.02,.10104,
.02,.09594,
0.0*
%
%ADD11MACRO11*%
%ADD27C,.02*%
%ADD28C,.006*%
%ADD31C,.07204*%
%ADD30C,.07704*%
%ADD29C,.11004*%
%ADD33R,.04704X.04354*%
%ADD32R,.04704X.04356*%
G75*
%LPD*%
G75*
G36*
G01X-6000Y-6000D02*
X570961D01*
Y262693D01*
X-6000D01*
Y-6000D01*
G37*
%LPC*%
G75*
G36*
G01X3937Y3004D02*
G02X3004Y3937I0J933D01*
G01Y87402D01*
G02X3937Y88335I933J0D01*
G01X192914D01*
G03X197886Y93307I-1J4973D01*
G01Y94240D01*
X269685D01*
G03X276626Y101181I0J6941D01*
G01Y252756D01*
G02X277559Y253689I933J0D01*
G01X561024D01*
G02X561957Y252756I0J-933D01*
G01Y3937D01*
G02X561024Y3004I-933J0D01*
G01X537402D01*
G02X536469Y3937I0J933D01*
G01Y71063D01*
G03X534701Y75691I-6941J0D01*
G02X534732Y76390I373J334D01*
G03X528540Y78574I-2527J2704D01*
G02X528045Y78004I-495J-70D01*
G01X477309D01*
G02X476814Y78574I0J500D01*
G03X469889Y80848I-3665J521D01*
G02X468949Y81085I-440J237D01*
G01Y94488D01*
G03X462008Y101429I-6941J0D01*
G01X379921D01*
G03X372980Y94488I0J-6941D01*
G01Y3937D01*
G02X372047Y3004I-933J0D01*
G01X3937D01*
G37*
%LPD*%
G75*
G36*
G01X510439Y83496D02*
X510440Y83497D01*
X510833Y83104D01*
X510832Y83103D01*
G02X504884Y89073I-2268J3688D01*
G01X504885Y89074D01*
X505278Y88681D01*
X505277Y88680D01*
G03X510439Y83496I3293J-1883D01*
G37*
G36*
G01X506727Y90126D02*
X506726Y90125D01*
X506333Y90518D01*
X506334Y90519D01*
G02X512282Y84549I2268J-3688D01*
G01X512281Y84548D01*
X511888Y84941D01*
X511889Y84942D01*
G03X506727Y90126I-3293J1883D01*
G37*
G36*
G01X494915D02*
X494914Y90125D01*
X494521Y90518D01*
X494522Y90519D01*
G02X500470Y84549I2268J-3688D01*
G01X500469Y84548D01*
X500076Y84941D01*
X500077Y84942D01*
G03X494915Y90126I-3293J1883D01*
G37*
G36*
G01X498627Y83496D02*
X498628Y83497D01*
X499021Y83104D01*
X499020Y83103D01*
G02X493072Y89073I-2268J3688D01*
G01X493073Y89074D01*
X493466Y88681D01*
X493465Y88680D01*
G03X498627Y83496I3293J-1883D01*
G37*
G36*
G01X399331Y201028D02*
G02Y206452I0J2712D01*
G01X404331D01*
G02Y201028I0J-2712D01*
G01X399331D01*
G37*
G36*
G01Y135280D02*
G02Y140704I0J2712D01*
G01X404331D01*
G02Y135280I0J-2712D01*
G01X399331D01*
G37*
G36*
G01X384331Y201028D02*
G02Y206452I0J2712D01*
G01X389331D01*
G02Y201028I0J-2712D01*
G01X384331D01*
G37*
G36*
G01X377951Y161364D02*
G02X372982Y166334I1J4970D01*
G01Y180114D01*
G02X377952Y185084I4971J-1D01*
G01X484252D01*
G02X489222Y180114I0J-4970D01*
G01Y166334D01*
G02X484252Y161364I-4970J0D01*
G01X377951D01*
G37*
G36*
G01X384331Y135280D02*
G02Y140704I0J2712D01*
G01X389331D01*
G02Y135280I0J-2712D01*
G01X384331D01*
G37*
G36*
G01X329126Y83334D02*
G02X325102I-2012J0D01*
G01Y87335D01*
G02X329126Y87334I2012J-1D01*
G01Y83334D01*
G37*
G36*
G01X329404Y103226D02*
G02Y99204I0J-2011D01*
G01X325403D01*
G02X325404Y103226I1J2011D01*
G01X329404D01*
G37*
G36*
G01X342886Y92311D02*
G02X338862I-2012J0D01*
G01Y96312D01*
G02X342886Y96311I2012J-1D01*
G01Y92311D01*
G37*
G36*
G01X345040Y83447D02*
G02X341016I-2012J0D01*
G01Y87448D01*
G02X345040Y87447I2012J-1D01*
G01Y83447D01*
G37*
G36*
G01X108287Y51816D02*
G02Y57240I0J2712D01*
G01X113287D01*
G02Y51816I0J-2712D01*
G01X108287D01*
G37*
G36*
G01Y7328D02*
G02Y12750I0J2711D01*
G01X113287D01*
G02Y7328I0J-2711D01*
G01X108287D01*
G37*
G36*
G01X93287Y51816D02*
G02Y57240I0J2712D01*
G01X98287D01*
G02Y51816I0J-2712D01*
G01X93287D01*
G37*
G36*
G01X188977Y50246D02*
G02X193946Y45276I-1J-4970D01*
G01Y43307D01*
G02X188977Y38338I-4970J1D01*
G01X82677D01*
G02X77708Y43307I0J4969D01*
G01Y45276D01*
G02X82677Y50246I4970J0D01*
G01X188977D01*
G37*
G36*
G01X98287Y12750D02*
G02Y7328I0J-2711D01*
G01X93287D01*
G02Y12750I0J2711D01*
G01X98287D01*
G37*
G54D31*
X312657Y66142D03*
Y107716D03*
G54D30*
X225097Y15039D03*
Y59528D03*
X516141Y142992D03*
Y208740D03*
G54D29*
X17715Y44095D03*
X525590Y240944D03*
X552795Y40157D03*
G54D33*
X297578Y94311D03*
X322106D03*
X308208D03*
X332736D03*
G54D32*
X297578Y85452D03*
X322106D03*
X308208D03*
X332736D03*
G54D26*
X496771Y86811D03*
X508583D03*
G54D16*
X60928Y64173D03*
X73567Y4087D03*
X75100Y36700D03*
X74635Y29153D03*
X76804Y61699D03*
X76600Y68000D03*
X208000Y90000D03*
X204500D03*
X220310Y4087D03*
X218600Y37400D03*
X213100Y83500D03*
X268045Y8270D03*
X258088Y21787D03*
X273551Y37112D03*
X279500Y116900D03*
X279437Y120731D03*
X322100Y26600D03*
X303900Y28900D03*
X313900Y27200D03*
X315166Y52172D03*
X309250Y127439D03*
X322042Y147196D03*
X310500Y184328D03*
X340000Y14667D03*
X324700Y16300D03*
X343028Y87447D03*
X327114Y87334D03*
X340874Y96311D03*
X325404Y101215D03*
X343028Y83447D03*
X327114Y83334D03*
X340874Y92311D03*
X329404Y101215D03*
X336238Y148951D03*
X351040Y34753D03*
X358900Y23928D03*
X506868Y166599D03*
G54D15*
X63713Y48425D03*
X65006Y43434D03*
X60469Y79819D03*
X56667Y83351D03*
X60393Y83934D03*
X52667Y83351D03*
X261719Y52314D03*
X261774Y48506D03*
X261840Y42259D03*
X261924Y38480D03*
X258240Y42259D03*
X258174Y48506D03*
X258119Y52314D03*
X258324Y38480D03*
X286638Y33917D03*
X282148Y51376D03*
X282093Y55184D03*
X278462Y51437D03*
X278407Y55245D03*
X281964Y47752D03*
X278278Y47813D03*
X284292Y61505D03*
X280555Y61542D03*
X299300Y144500D03*
X300000Y164900D03*
X302000Y133500D03*
X301913Y129821D03*
X303000Y144400D03*
X309500Y145000D03*
X303600Y164800D03*
X320332Y160022D03*
X316332D03*
Y164522D03*
X320332D03*
X316332Y155668D03*
X320332D03*
X316438Y151436D03*
X320438D03*
X318500Y193500D03*
X314500D03*
X318500Y188500D03*
X314500D03*
X314454Y213250D03*
X314500Y203500D03*
X318500D03*
Y198500D03*
X314500D03*
X332778Y20000D03*
X328508Y41629D03*
X328424Y45408D03*
X332508Y41629D03*
X332424Y45408D03*
X332565Y49028D03*
X332614Y52663D03*
X328565Y49028D03*
X328614Y52663D03*
X336698Y154738D03*
X340698D03*
X340779Y158381D03*
Y162024D03*
X336779D03*
Y158381D03*
X340779Y165718D03*
X336779D03*
X332000Y183500D03*
X339000Y193500D03*
X335000D03*
Y203500D03*
X339000D03*
Y198500D03*
X335000D03*
X347421Y8568D03*
X350479Y10768D03*
X353229Y52810D03*
X349229D03*
X353095Y45538D03*
X353094Y49157D03*
X352971Y41813D03*
X349095Y45538D03*
X349094Y49157D03*
X348971Y41813D03*
X364750Y37750D03*
X354580Y102351D03*
X350569Y102263D03*
X358824Y108849D03*
X352501Y105640D03*
X350827Y108976D03*
X348696Y105396D03*
X356501Y105640D03*
X354827Y108976D03*
X480101Y230616D03*
X483700Y230522D03*
G54D19*
X137087Y23464D03*
X133937D03*
X130787D03*
X127637D03*
X124487D03*
X137087Y67953D03*
X133937D03*
X130787D03*
X127637D03*
X124487D03*
X428131Y151417D03*
X424981D03*
X421831D03*
X418681D03*
X415531D03*
X428131Y217165D03*
X424981D03*
X421831D03*
X418681D03*
X415531D03*
G54D20*
X225097Y15039D03*
Y59528D03*
X516141Y142992D03*
Y208740D03*
G54D17*
X93287Y10039D03*
Y54528D03*
X113287Y10039D03*
X108287D03*
X98287D03*
X113287Y54528D03*
X108287D03*
X98287D03*
X153287Y10039D03*
X148287D03*
X143287D03*
X153287Y54528D03*
X148287D03*
X143287D03*
X183287Y10039D03*
X178287D03*
X173287D03*
X183287Y54528D03*
X178287D03*
X173287D03*
X208287Y10039D03*
X203287D03*
X193287D03*
X188287D03*
X208287Y54528D03*
X203287D03*
X193287D03*
X188287D03*
X213287Y10039D03*
Y54528D03*
X389331Y137992D03*
X384331D03*
X389331Y203740D03*
X384331D03*
X404331Y137992D03*
X399331D03*
X404331Y203740D03*
X399331D03*
X434331Y137992D03*
Y203740D03*
X444331Y137992D03*
X439331D03*
X444331Y203740D03*
X439331D03*
X479331Y137992D03*
X474331D03*
X469331D03*
X464331D03*
X479331Y203740D03*
X474331D03*
X469331D03*
X464331D03*
X504331Y137992D03*
X499331D03*
X494331D03*
X484331D03*
X504331Y203740D03*
X499331D03*
X494331D03*
X484331D03*
G54D22*
X312657Y66142D03*
Y107716D03*
G54D25*
X484960Y86811D03*
X520394D03*
G54D24*
X473149Y79094D03*
X532205D03*
G54D13*
X5500Y48299D03*
X7960Y85839D03*
X42701Y5500D03*
X48316Y32530D03*
X44316D03*
Y28681D03*
X48316D03*
X44278Y24717D03*
X48278D03*
X49374Y56390D03*
X45374D03*
X45336Y52426D03*
X49336D03*
X41000Y79500D03*
Y75500D03*
X37000Y79500D03*
Y75500D03*
X49374Y60239D03*
X45374D03*
X27960Y85839D03*
X67960D03*
X87960D03*
X107960D03*
X127960D03*
X147960D03*
X167960D03*
X207675Y38907D03*
X204000Y82000D03*
X208000D03*
Y86000D03*
X204000D03*
X187960Y85839D03*
X214906Y39494D03*
X211337Y38963D03*
X222206Y41500D03*
X217880Y83600D03*
X242500Y27000D03*
X246500D03*
X243000Y47500D03*
X247000D03*
X244727Y76591D03*
X244870Y80370D03*
X248866Y76464D03*
X248811Y80272D03*
X281221Y33971D03*
X293146Y81023D03*
X293141Y97997D03*
X284798Y149063D03*
X284905Y160541D03*
X284940Y156881D03*
X284798Y152687D03*
X289800Y165000D03*
X297698Y191563D03*
Y195187D03*
X279122Y174213D03*
Y194213D03*
X297840Y199381D03*
X297805Y203041D03*
X279122Y214213D03*
Y234213D03*
X282142Y251193D03*
X322701Y5500D03*
X321373Y56703D03*
X303734Y89882D03*
X303700Y140700D03*
X315048Y133300D03*
X300754Y205956D03*
X304000Y213000D03*
X322142Y251193D03*
X332666Y27700D03*
X329962Y56703D03*
X326423Y183632D03*
X326000Y217500D03*
X342142Y251193D03*
X357672Y4602D03*
X345690Y20300D03*
X362142Y251193D03*
X382142D03*
X402142D03*
X422142D03*
X442142D03*
X471445Y93346D03*
X476600Y227250D03*
X462142Y251193D03*
X502868Y166448D03*
X502142Y251193D03*
X482142D03*
X519980Y226295D03*
X523642Y226351D03*
X520017Y230070D03*
X523642Y230014D03*
X522142Y251193D03*
X538965Y41992D03*
Y61992D03*
X559461Y68512D03*
Y88512D03*
Y108512D03*
Y148512D03*
Y128512D03*
Y168512D03*
Y188512D03*
Y208512D03*
G54D10*
X-14755Y415558D03*
X-12454Y45507D03*
X17715Y44095D03*
X29461Y718854D03*
X141466Y655356D03*
X395935Y76695D03*
X508569Y15093D03*
X525590Y240944D03*
X552795Y40157D03*
X554126Y315939D03*
Y685624D03*
G54D14*
X68112Y15039D03*
Y59528D03*
X233462Y15039D03*
Y59528D03*
X359156Y142992D03*
Y208740D03*
X524506Y142992D03*
Y208740D03*
G54D21*
X295472Y65571D03*
Y108287D03*
X330590Y65571D03*
Y108287D03*
G54D18*
X88287Y10039D03*
Y54528D03*
X118287Y10039D03*
X103287D03*
X118287Y54528D03*
X103287D03*
X140237Y23464D03*
X121337D03*
X140237Y67953D03*
X121337D03*
X163287Y10039D03*
X158287D03*
X163287Y54528D03*
X158287D03*
X168287Y10039D03*
Y54528D03*
X198287Y10039D03*
Y54528D03*
X313617Y81023D03*
X321440Y101571D03*
X337406Y79575D03*
X341133Y80298D03*
X326892Y79371D03*
X338145Y98740D03*
X337670Y90976D03*
X332822Y103140D03*
X327057Y90943D03*
X345642Y90134D03*
X379331Y137992D03*
Y203740D03*
X409331Y137992D03*
X394331D03*
X412381Y151417D03*
Y217165D03*
X409331Y203740D03*
X394331D03*
X431281Y151417D03*
Y217165D03*
X459331Y137992D03*
X454331D03*
X449331D03*
X459331Y203740D03*
X454331D03*
X449331D03*
X489331Y137992D03*
Y203740D03*
G54D23*
X308208Y101945D03*
G54D12*
X15748Y67008D03*
X303150Y13780D03*
Y242913D03*
X551181Y13780D03*
G54D11*
X15748Y15827D03*
X551181Y242913D03*
%LPC*%
G75*
G54D27*
G01X-139981Y-146685D02*
G02I-12000J0D01*
G01X-145131D02*
G02I-6850J0D01*
G01X-135981D02*
X-167981D01*
G01X-135981Y-162685D02*
Y-242685D01*
G01D02*
X971619D01*
G01X-135981Y-198185D02*
X971619D01*
G01X-151981Y-162685D02*
Y-130685D01*
G01X-135981Y-162685D02*
X971619D01*
G01X184119D02*
Y-242685D01*
G01X321619Y-162685D02*
Y-242685D01*
G01X436619Y-162685D02*
Y-242685D01*
G01X604119Y-162685D02*
Y-242685D01*
G01X774119Y-162685D02*
Y-242685D01*
G01X971619Y-162685D02*
Y-242685D01*
G01X999619Y-146685D02*
G02I-12000J0D01*
G01X1003619D02*
X971619D01*
G01X994469D02*
G02I-6850J0D01*
G01X987619Y-162685D02*
Y-130685D01*
G54D28*
G01X-116181Y-215185D02*
Y-232685D01*
G01X-121203Y-215185D02*
X-111159D01*
G01X-103048Y-232685D02*
Y-215185D01*
X-97808D01*
X-96061Y-216060D01*
X-94751Y-218102D01*
X-94314Y-220435D01*
X-94751Y-222768D01*
X-95843Y-224518D01*
X-97808Y-225394D01*
X-103048D01*
G01X-58878Y-216644D02*
X-60188Y-215768D01*
X-61716Y-215185D01*
X-63463D01*
X-65428Y-216060D01*
X-66956Y-217518D01*
X-68048Y-219269D01*
X-68921Y-222185D01*
X-69140Y-224810D01*
X-68703Y-227435D01*
X-68048Y-229185D01*
X-66738Y-230935D01*
X-65209Y-232102D01*
X-63681Y-232685D01*
X-62153D01*
X-60624Y-232102D01*
X-59314Y-231227D01*
X-58222Y-230061D01*
G01X-49893Y-232685D02*
Y-215185D01*
G01Y-223643D02*
X-48801Y-222185D01*
X-47709Y-221310D01*
X-45963Y-221019D01*
X-44653Y-221310D01*
X-43124Y-222477D01*
X-42469Y-224227D01*
Y-232685D01*
G01X-24751D02*
Y-221019D01*
G01Y-223060D02*
X-25624Y-221894D01*
X-26935Y-221310D01*
X-28463Y-221019D01*
X-29991Y-221602D01*
X-31301Y-222768D01*
X-32175Y-224518D01*
X-32611Y-226852D01*
X-32175Y-229185D01*
X-31301Y-230935D01*
X-29991Y-232102D01*
X-28463Y-232685D01*
X-26935Y-232393D01*
X-25624Y-231519D01*
X-24751Y-230352D01*
G01X-14893Y-232685D02*
Y-221019D01*
G01Y-223935D02*
X-14019Y-222477D01*
X-12709Y-221310D01*
X-10963Y-221019D01*
X-9435Y-221310D01*
X-8124Y-222477D01*
X-7469Y-224518D01*
Y-232685D01*
G01X2607D02*
Y-221019D01*
G01Y-223935D02*
X3481Y-222477D01*
X4791Y-221310D01*
X6537Y-221019D01*
X8065Y-221310D01*
X9376Y-222477D01*
X10031Y-224518D01*
Y-232685D01*
G01X20544Y-224810D02*
X27531D01*
X26876Y-222768D01*
X25784Y-221602D01*
X24256Y-221019D01*
X22727Y-221310D01*
X21417Y-222185D01*
X20544Y-224227D01*
X20107Y-225977D01*
Y-227727D01*
X20544Y-229477D01*
X21636Y-231227D01*
X22946Y-232393D01*
X24474Y-232685D01*
X26002Y-232102D01*
X27531Y-230352D01*
G01X41319Y-232685D02*
Y-215185D01*
G01X71734Y-232685D02*
Y-215185D01*
G01X80904D02*
Y-232685D01*
G01Y-223935D02*
X71734D01*
G01X89016Y-232685D02*
Y-215185D01*
X93382D01*
X95129Y-216060D01*
X96439Y-217227D01*
X97531Y-218976D01*
X98404Y-221019D01*
X98622Y-223935D01*
X98404Y-226852D01*
X97531Y-228894D01*
X96439Y-230644D01*
X95129Y-231810D01*
X93382Y-232685D01*
X89016D01*
G01X106516D02*
Y-215185D01*
X110882D01*
X112629Y-216060D01*
X113939Y-217227D01*
X115031Y-218976D01*
X115904Y-221019D01*
X116122Y-223935D01*
X115904Y-226852D01*
X115031Y-228894D01*
X113939Y-230644D01*
X112629Y-231810D01*
X110882Y-232685D01*
X106516D01*
G01X148065Y-223352D02*
X148939Y-222477D01*
X149594Y-221019D01*
X150031Y-218976D01*
X149594Y-217227D01*
X148721Y-216060D01*
X147192Y-215185D01*
X141297D01*
Y-232685D01*
X148502D01*
X150031Y-231519D01*
X150904Y-229768D01*
X151341Y-227727D01*
X150904Y-225685D01*
X149594Y-223935D01*
X148065Y-223352D01*
X141297D01*
G01X159452Y-232685D02*
Y-215185D01*
X164692D01*
X166439Y-216060D01*
X167749Y-218102D01*
X168186Y-220435D01*
X167749Y-222768D01*
X166657Y-224518D01*
X164692Y-225394D01*
X159452D01*
G01X-16858Y-187685D02*
Y-170185D01*
X-11181Y-184768D01*
X-5504Y-170185D01*
Y-187685D01*
G01X6319D02*
X5009Y-187393D01*
X3699Y-186227D01*
X2825Y-184185D01*
X2389Y-181852D01*
X2825Y-179518D01*
X3699Y-177477D01*
X5009Y-176310D01*
X6319Y-176019D01*
X7629Y-176310D01*
X8939Y-177477D01*
X9812Y-179518D01*
X10031Y-181852D01*
X9812Y-184185D01*
X8939Y-186227D01*
X7629Y-187393D01*
X6319Y-187685D01*
G01X27749Y-170185D02*
Y-187685D01*
G01Y-185061D02*
X26876Y-186519D01*
X25565Y-187393D01*
X24037Y-187685D01*
X22291Y-187102D01*
X20981Y-185644D01*
X20107Y-183894D01*
X19889Y-181852D01*
X20107Y-179810D01*
X20981Y-178060D01*
X22291Y-176602D01*
X24037Y-176019D01*
X25565Y-176310D01*
X26657Y-176894D01*
X27749Y-178060D01*
G01X38044Y-179810D02*
X45031D01*
X44376Y-177768D01*
X43284Y-176602D01*
X41756Y-176019D01*
X40227Y-176310D01*
X38917Y-177185D01*
X38044Y-179227D01*
X37607Y-180977D01*
Y-182727D01*
X38044Y-184477D01*
X39136Y-186227D01*
X40446Y-187393D01*
X41974Y-187685D01*
X43502Y-187102D01*
X45031Y-185352D01*
G01X58819Y-187685D02*
Y-170185D01*
G01X204702Y-187685D02*
Y-170185D01*
X209942D01*
X211689Y-171060D01*
X212999Y-173102D01*
X213436Y-175435D01*
X212999Y-177768D01*
X211907Y-179518D01*
X209942Y-180394D01*
X204702D01*
G01X231372Y-171644D02*
X230062Y-170768D01*
X228534Y-170185D01*
X226787D01*
X224822Y-171060D01*
X223294Y-172518D01*
X222202Y-174269D01*
X221329Y-177185D01*
X221110Y-179810D01*
X221547Y-182435D01*
X222202Y-184185D01*
X223512Y-185935D01*
X225041Y-187102D01*
X226569Y-187685D01*
X228097D01*
X229626Y-187102D01*
X230936Y-186227D01*
X232028Y-185061D01*
G01X245815Y-178352D02*
X246689Y-177477D01*
X247344Y-176019D01*
X247781Y-173976D01*
X247344Y-172227D01*
X246471Y-171060D01*
X244942Y-170185D01*
X239047D01*
Y-187685D01*
X246252D01*
X247781Y-186519D01*
X248654Y-184768D01*
X249091Y-182727D01*
X248654Y-180685D01*
X247344Y-178935D01*
X245815Y-178352D01*
X239047D01*
G01X255019Y-193518D02*
X268119D01*
G01X274047Y-187685D02*
Y-170185D01*
X284091Y-187685D01*
Y-170185D01*
G01X296569Y-187685D02*
X294822Y-187393D01*
X293294Y-186227D01*
X291984Y-184477D01*
X291110Y-182435D01*
X290674Y-180102D01*
Y-177768D01*
X291110Y-175435D01*
X291984Y-173393D01*
X293294Y-171644D01*
X294822Y-170477D01*
X296569Y-170185D01*
X298315Y-170477D01*
X299844Y-171644D01*
X301154Y-173393D01*
X302028Y-175435D01*
X302464Y-177768D01*
Y-180102D01*
X302028Y-182435D01*
X301154Y-184477D01*
X299844Y-186227D01*
X298315Y-187393D01*
X296569Y-187685D01*
G01X217819Y-232685D02*
Y-215185D01*
X215199Y-218685D01*
G01Y-232685D02*
X220439D01*
G01X234882D02*
X235319Y-228894D01*
X235974Y-225685D01*
X236847Y-222768D01*
X237939Y-219560D01*
X239686Y-215185D01*
X230952D01*
G01X248016Y-229185D02*
X249325Y-231227D01*
X251072Y-232393D01*
X253037Y-232685D01*
X254784Y-232393D01*
X256531Y-230935D01*
X257622Y-229185D01*
X257841Y-227435D01*
X257404Y-225394D01*
X255876Y-223935D01*
X254347Y-223352D01*
X252382D01*
G01X254347D02*
X255657Y-222477D01*
X256749Y-221019D01*
X257186Y-219269D01*
X256749Y-217518D01*
X255657Y-216060D01*
X253692Y-215185D01*
X251727Y-215477D01*
X249762Y-216644D01*
G01X270319Y-215185D02*
X268572Y-215768D01*
X267262Y-217227D01*
X266389Y-218976D01*
X265734Y-221310D01*
X265516Y-223935D01*
X265734Y-226560D01*
X266389Y-228894D01*
X267262Y-230644D01*
X268572Y-232102D01*
X270319Y-232685D01*
X272065Y-232102D01*
X273376Y-230644D01*
X274249Y-228894D01*
X274904Y-226560D01*
X275122Y-223935D01*
X274904Y-221310D01*
X274249Y-218976D01*
X273376Y-217227D01*
X272065Y-215768D01*
X270319Y-215185D01*
G01X287819Y-232685D02*
Y-215185D01*
X285199Y-218685D01*
G01Y-232685D02*
X290439D01*
G01X365784Y-230352D02*
X367531Y-231810D01*
X369496Y-232685D01*
X371242D01*
X372989Y-231810D01*
X374299Y-230352D01*
X374954Y-228310D01*
X374517Y-226269D01*
X373426Y-224518D01*
X371461Y-223352D01*
X368841Y-222768D01*
X367312Y-221602D01*
X366657Y-219560D01*
X367094Y-217518D01*
X368186Y-216060D01*
X369714Y-215185D01*
X371242D01*
X372771Y-215768D01*
X374081Y-217227D01*
G01X382410Y-232685D02*
X387869Y-215185D01*
X393328Y-232685D01*
G01X391362Y-226560D02*
X384375D01*
G01X347410Y-170185D02*
X352869Y-187685D01*
X358328Y-170185D01*
G01X374736Y-187685D02*
X366002D01*
Y-170185D01*
X374736D01*
G01X371242Y-178643D02*
X366002D01*
G01X383502Y-187685D02*
Y-170185D01*
X388961D01*
X390707Y-171060D01*
X391799Y-172227D01*
X392236Y-174560D01*
X391799Y-176894D01*
X390489Y-178352D01*
X388961Y-179227D01*
X383502D01*
G01X388961D02*
X392236Y-187685D01*
G01X405369Y-188268D02*
X404932Y-187977D01*
Y-187393D01*
X405369Y-187102D01*
X405806Y-187393D01*
Y-187977D01*
X405369Y-188268D01*
G01X559686Y-215185D02*
Y-232685D01*
X550952D01*
G01X542622Y-230061D02*
X541313Y-231519D01*
X539784Y-232393D01*
X537819Y-232685D01*
X535854Y-232102D01*
X534326Y-230935D01*
X533234Y-228894D01*
X533016Y-226560D01*
X533452Y-224227D01*
X534544Y-222768D01*
X536073Y-221602D01*
X537601Y-221310D01*
X539129Y-221602D01*
X541094Y-222768D01*
X540439Y-215185D01*
X534544D01*
G01X519009Y-223935D02*
X514642D01*
Y-229185D01*
X515952Y-230935D01*
X517481Y-232102D01*
X519664Y-232685D01*
X521847Y-232102D01*
X523376Y-230935D01*
X524686Y-229185D01*
X525559Y-227143D01*
X525996Y-224810D01*
Y-222768D01*
X525559Y-221019D01*
X524686Y-218976D01*
X523376Y-217227D01*
X522066Y-216060D01*
X520319Y-215185D01*
X518791D01*
X517044Y-215768D01*
X515734Y-216935D01*
G01X507841Y-232685D02*
Y-215185D01*
X497797Y-232685D01*
Y-215185D01*
G01X490122Y-232685D02*
Y-215185D01*
X485756D01*
X484009Y-216060D01*
X482699Y-217227D01*
X481607Y-218976D01*
X480734Y-221019D01*
X480516Y-223935D01*
X480734Y-226852D01*
X481607Y-228894D01*
X482699Y-230644D01*
X484009Y-231810D01*
X485756Y-232685D01*
X490122D01*
G01X480952Y-170185D02*
Y-187685D01*
X489686D01*
G01X506749D02*
Y-176019D01*
G01Y-178060D02*
X505876Y-176894D01*
X504565Y-176310D01*
X503037Y-176019D01*
X501509Y-176602D01*
X500199Y-177768D01*
X499325Y-179518D01*
X498889Y-181852D01*
X499325Y-184185D01*
X500199Y-185935D01*
X501509Y-187102D01*
X503037Y-187685D01*
X504565Y-187393D01*
X505876Y-186519D01*
X506749Y-185352D01*
G01X515734Y-192935D02*
X517044Y-193518D01*
X518791Y-192935D01*
X519882Y-191769D01*
X520756Y-190310D01*
X522065Y-185644D01*
X524904Y-176019D01*
G01X517917D02*
X522065Y-185644D01*
G01X534544Y-179810D02*
X541531D01*
X540876Y-177768D01*
X539784Y-176602D01*
X538256Y-176019D01*
X536727Y-176310D01*
X535417Y-177185D01*
X534544Y-179227D01*
X534107Y-180977D01*
Y-182727D01*
X534544Y-184477D01*
X535636Y-186227D01*
X536946Y-187393D01*
X538474Y-187685D01*
X540002Y-187102D01*
X541531Y-185352D01*
G01X552262Y-187685D02*
Y-176019D01*
G01Y-178352D02*
X553354Y-177185D01*
X554446Y-176310D01*
X555974Y-176019D01*
X557065Y-176310D01*
X558376Y-177185D01*
G01X623066Y-187685D02*
Y-170185D01*
X627432D01*
X629179Y-171060D01*
X630489Y-172227D01*
X631581Y-173976D01*
X632454Y-176019D01*
X632672Y-178935D01*
X632454Y-181852D01*
X631581Y-183894D01*
X630489Y-185644D01*
X629179Y-186810D01*
X627432Y-187685D01*
X623066D01*
G01X642094Y-179810D02*
X649081D01*
X648426Y-177768D01*
X647334Y-176602D01*
X645806Y-176019D01*
X644277Y-176310D01*
X642967Y-177185D01*
X642094Y-179227D01*
X641657Y-180977D01*
Y-182727D01*
X642094Y-184477D01*
X643186Y-186227D01*
X644496Y-187393D01*
X646024Y-187685D01*
X647552Y-187102D01*
X649081Y-185352D01*
G01X659594Y-185644D02*
X660686Y-186810D01*
X662214Y-187685D01*
X663524D01*
X664834Y-187102D01*
X665707Y-186227D01*
X666144Y-185061D01*
X665926Y-183310D01*
X665052Y-182435D01*
X661122Y-180685D01*
X660249Y-178643D01*
X660686Y-177185D01*
X661559Y-176310D01*
X662869Y-176019D01*
X664179Y-176310D01*
X665489Y-177185D01*
G01X680369Y-176019D02*
Y-187685D01*
G01Y-171352D02*
X679932Y-171060D01*
Y-170477D01*
X680369Y-170185D01*
X680806Y-170477D01*
Y-171060D01*
X680369Y-171352D01*
G01X694812Y-192060D02*
X696341Y-193227D01*
X698087Y-193518D01*
X699615Y-193227D01*
X700926Y-191769D01*
X701799Y-189727D01*
Y-176019D01*
G01Y-178352D02*
X700926Y-177185D01*
X699615Y-176310D01*
X698087Y-176019D01*
X696341Y-176602D01*
X695249Y-177768D01*
X694375Y-179810D01*
X693939Y-181852D01*
X694157Y-183602D01*
X695031Y-185644D01*
X696341Y-187102D01*
X698087Y-187685D01*
X699397Y-187393D01*
X700926Y-186227D01*
X701799Y-185061D01*
G01X711657Y-187685D02*
Y-176019D01*
G01Y-178935D02*
X712531Y-177477D01*
X713841Y-176310D01*
X715587Y-176019D01*
X717115Y-176310D01*
X718426Y-177477D01*
X719081Y-179518D01*
Y-187685D01*
G01X729594Y-179810D02*
X736581D01*
X735926Y-177768D01*
X734834Y-176602D01*
X733306Y-176019D01*
X731777Y-176310D01*
X730467Y-177185D01*
X729594Y-179227D01*
X729157Y-180977D01*
Y-182727D01*
X729594Y-184477D01*
X730686Y-186227D01*
X731996Y-187393D01*
X733524Y-187685D01*
X735052Y-187102D01*
X736581Y-185352D01*
G01X747312Y-187685D02*
Y-176019D01*
G01Y-178352D02*
X748404Y-177185D01*
X749496Y-176310D01*
X751024Y-176019D01*
X752115Y-176310D01*
X753426Y-177185D01*
G01X664179Y-223935D02*
X668546D01*
Y-229185D01*
X667236Y-230935D01*
X665707Y-232102D01*
X663524Y-232685D01*
X661341Y-232102D01*
X659812Y-230935D01*
X658502Y-229185D01*
X657629Y-227143D01*
X657192Y-224810D01*
Y-222768D01*
X657629Y-221019D01*
X658502Y-218976D01*
X659812Y-217227D01*
X661122Y-216060D01*
X662869Y-215185D01*
X664397D01*
X666144Y-215768D01*
X667454Y-216935D01*
G01X684736Y-232685D02*
X676002D01*
Y-215185D01*
X684736D01*
G01X681242Y-223643D02*
X676002D01*
G01X693502Y-215185D02*
Y-232685D01*
X702236D01*
G01X715369D02*
X713622Y-232393D01*
X712094Y-231227D01*
X710784Y-229477D01*
X709910Y-227435D01*
X709474Y-225102D01*
Y-222768D01*
X709910Y-220435D01*
X710784Y-218393D01*
X712094Y-216644D01*
X713622Y-215477D01*
X715369Y-215185D01*
X717115Y-215477D01*
X718644Y-216644D01*
X719954Y-218393D01*
X720828Y-220435D01*
X721264Y-222768D01*
Y-225102D01*
X720828Y-227435D01*
X719954Y-229477D01*
X718644Y-231227D01*
X717115Y-232393D01*
X715369Y-232685D01*
G01X794069Y-215185D02*
X792322Y-215768D01*
X791012Y-217227D01*
X790139Y-218976D01*
X789484Y-221310D01*
X789266Y-223935D01*
X789484Y-226560D01*
X790139Y-228894D01*
X791012Y-230644D01*
X792322Y-232102D01*
X794069Y-232685D01*
X795815Y-232102D01*
X797126Y-230644D01*
X797999Y-228894D01*
X798654Y-226560D01*
X798872Y-223935D01*
X798654Y-221310D01*
X797999Y-218976D01*
X797126Y-217227D01*
X795815Y-215768D01*
X794069Y-215185D01*
G01X807421Y-225394D02*
X808949Y-223352D01*
X810259Y-222185D01*
X812006Y-221602D01*
X813534Y-222185D01*
X814626Y-223352D01*
X815499Y-225102D01*
X815717Y-227143D01*
X815499Y-228894D01*
X814626Y-230644D01*
X813315Y-232102D01*
X811787Y-232685D01*
X810041Y-232102D01*
X808512Y-230352D01*
X807639Y-227727D01*
X807421Y-224810D01*
X807857Y-221019D01*
X808512Y-218976D01*
X809604Y-216935D01*
X811132Y-215477D01*
X812661Y-215185D01*
X814189Y-215768D01*
X815281Y-217227D01*
G01X825139Y-233268D02*
X832999Y-215185D01*
G01X842421Y-218102D02*
X843731Y-216352D01*
X845259Y-215477D01*
X847006Y-215185D01*
X849189Y-215768D01*
X850717Y-217227D01*
X851154Y-218976D01*
X850936Y-220727D01*
X850062Y-222185D01*
X845696Y-225102D01*
X843731Y-227143D01*
X842421Y-230061D01*
X841984Y-232685D01*
X851154D01*
G01X859921Y-218102D02*
X861231Y-216352D01*
X862759Y-215477D01*
X864506Y-215185D01*
X866689Y-215768D01*
X868217Y-217227D01*
X868654Y-218976D01*
X868436Y-220727D01*
X867562Y-222185D01*
X863196Y-225102D01*
X861231Y-227143D01*
X859921Y-230061D01*
X859484Y-232685D01*
X868654D01*
G01X877639Y-233268D02*
X885499Y-215185D01*
G01X894921Y-218102D02*
X896231Y-216352D01*
X897759Y-215477D01*
X899506Y-215185D01*
X901689Y-215768D01*
X903217Y-217227D01*
X903654Y-218976D01*
X903436Y-220727D01*
X902562Y-222185D01*
X898196Y-225102D01*
X896231Y-227143D01*
X894921Y-230061D01*
X894484Y-232685D01*
X903654D01*
G01X916569Y-215185D02*
X914822Y-215768D01*
X913512Y-217227D01*
X912639Y-218976D01*
X911984Y-221310D01*
X911766Y-223935D01*
X911984Y-226560D01*
X912639Y-228894D01*
X913512Y-230644D01*
X914822Y-232102D01*
X916569Y-232685D01*
X918315Y-232102D01*
X919626Y-230644D01*
X920499Y-228894D01*
X921154Y-226560D01*
X921372Y-223935D01*
X921154Y-221310D01*
X920499Y-218976D01*
X919626Y-217227D01*
X918315Y-215768D01*
X916569Y-215185D01*
G01X934069Y-232685D02*
Y-215185D01*
X931449Y-218685D01*
G01Y-232685D02*
X936689D01*
G01X951132D02*
X951569Y-228894D01*
X952224Y-225685D01*
X953097Y-222768D01*
X954189Y-219560D01*
X955936Y-215185D01*
X947202D01*
G01X841766Y-187685D02*
Y-170185D01*
X846132D01*
X847879Y-171060D01*
X849189Y-172227D01*
X850281Y-173976D01*
X851154Y-176019D01*
X851372Y-178935D01*
X851154Y-181852D01*
X850281Y-183894D01*
X849189Y-185644D01*
X847879Y-186810D01*
X846132Y-187685D01*
X841766D01*
G01X867999D02*
Y-176019D01*
G01Y-178060D02*
X867126Y-176894D01*
X865815Y-176310D01*
X864287Y-176019D01*
X862759Y-176602D01*
X861449Y-177768D01*
X860575Y-179518D01*
X860139Y-181852D01*
X860575Y-184185D01*
X861449Y-185935D01*
X862759Y-187102D01*
X864287Y-187685D01*
X865815Y-187393D01*
X867126Y-186519D01*
X867999Y-185352D01*
G01X881569Y-170185D02*
Y-187685D01*
G01X878512Y-176019D02*
X884626D01*
G01X895794Y-179810D02*
X902781D01*
X902126Y-177768D01*
X901034Y-176602D01*
X899506Y-176019D01*
X897977Y-176310D01*
X896667Y-177185D01*
X895794Y-179227D01*
X895357Y-180977D01*
Y-182727D01*
X895794Y-184477D01*
X896886Y-186227D01*
X898196Y-187393D01*
X899724Y-187685D01*
X901252Y-187102D01*
X902781Y-185352D01*
M02*
